# S9S_MB_2U (Grand Teton) — schematic parts with pin connectivity, parts 1620–1620 of 6093; source: Cadence DE-HDL packaged netlist (pstxprt.dat, pstxnet.dat, pstchip.dat)

J27  SCONN288_ADR50017P130CC  SCONN288_ADR50017-P130CC IO  pkg DDR288S_1-1VXB  page 108
  1  VIN_BULK0  POWER  = P12V_S3_AUX_CPU1_NVDIMM
  2  RFU0  TRI  = TP_CHF_CPU1_DIMM1_FRU_0
  3  VIN_MGMT  POWER  = P3V3_AUX
  4  HSCL  IN  = I3C_SPD_DDREFGH_CPU1_LVC1_SCL_2
  5  HSDA  BI  = I3C_SPD_DDREFGH_CPU1_LVC1_SDA
  6  VSS0  POWER  = GND
  7  DQ0_A  BI  = M_F_CPU1_SA_DQ<0>
  8  VSS1  POWER  = GND
  9  DQ1_A  BI  = M_F_CPU1_SA_DQ<1>
  10  VSS2  POWER  = GND
  11  DQS0_A_T  BI  = M_F_CPU1_SA_DQS_DP<0>
  12  DQS0_A_C  BI  = M_F_CPU1_SA_DQS_DN<0>
  13  VSS3  POWER  = GND
  14  DQ4_A  BI  = M_F_CPU1_SA_DQ<4>
  15  VSS4  POWER  = GND
  16  DQ5_A  BI  = M_F_CPU1_SA_DQ<5>
  17  VSS5  POWER  = GND
  18  DQ8_A  BI  = M_F_CPU1_SA_DQ<8>
  19  VSS6  POWER  = GND
  20  DQ9_A  BI  = M_F_CPU1_SA_DQ<9>
  21  VSS7  POWER  = GND
  22  DQS1_A_T  BI  = M_F_CPU1_SA_DQS_DP<1>
  23  DQS1_A_C  BI  = M_F_CPU1_SA_DQS_DN<1>
  24  VSS8  POWER  = GND
  25  DQ12_A  BI  = M_F_CPU1_SA_DQ<12>
  26  VSS9  POWER  = GND
  27  DQ13_A  BI  = M_F_CPU1_SA_DQ<13>
  28  VSS10  POWER  = GND
  29  DQ16_A  BI  = M_F_CPU1_SA_DQ<16>
  30  VSS11  POWER  = GND
  31  DQ17_A  BI  = M_F_CPU1_SA_DQ<17>
  32  VSS12  POWER  = GND
  33  DQS2_A_T  BI  = M_F_CPU1_SA_DQS_DP<2>
  34  DQS2_A_C  BI  = M_F_CPU1_SA_DQS_DN<2>
  35  VSS13  POWER  = GND
  36  DQ20_A  BI  = M_F_CPU1_SA_DQ<20>
  37  VSS14  POWER  = GND
  38  DQ21_A  BI  = M_F_CPU1_SA_DQ<21>
  39  VSS15  POWER  = GND
  40  DQ24_A  BI  = M_F_CPU1_SA_DQ<24>
  41  VSS16  POWER  = GND
  42  DQ25_A  BI  = M_F_CPU1_SA_DQ<25>
  43  VSS17  POWER  = GND
  44  DQS3_A_T  BI  = M_F_CPU1_SA_DQS_DP<3>
  45  DQS3_A_C  BI  = M_F_CPU1_SA_DQS_DN<3>
  46  VSS18  POWER  = GND
  47  DQ28_A  BI  = M_F_CPU1_SA_DQ<28>
  48  VSS19  POWER  = GND
  49  DQ29_A  BI  = M_F_CPU1_SA_DQ<29>
  50  VSS20  POWER  = GND
  51  CB0_A  BI  = M_F_CPU1_SA_CB<0>
  52  VSS21  POWER  = GND
  53  CB1_A  BI  = M_F_CPU1_SA_CB<1>
  54  VSS22  POWER  = GND
  55  DQS4_A_T  BI  = M_F_CPU1_SA_DQS_DP<4>
  56  DQS4_A_C  BI  = M_F_CPU1_SA_DQS_DN<4>
  57  VSS23  POWER  = GND
  58  CB4_A  BI  = M_F_CPU1_SA_CB<4>
  59  VSS24  POWER  = GND
  60  CB5_A  BI  = M_F_CPU1_SA_CB<5>
  61  VSS25  POWER  = GND
  62  ALERT_N  OUT  = M_F_CPU1_ALERT_N
  63  VSS26  POWER  = GND
  64  CS0_A_N  IN  = M_F_CPU1_SA_CS_N<0>
  65  VSS27  POWER  = GND
  66  CA0_A  IN  = M_F_CPU1_SA_CA<0>
  67  VSS28  POWER  = GND
  68  CA2_A  IN  = M_F_CPU1_SA_CA<2>
  69  VSS29  POWER  = GND
  70  CA4_A  IN  = M_F_CPU1_SA_CA<4>
  71  VSS30  POWER  = GND
  72  CA6_A  IN  = M_F_CPU1_SA_CA<6>
  73  VSS31  POWER  = GND
  74  PAR_A  IN  = M_F_CPU1_SA_PAR
  75  VSS32  POWER  = GND
  76  CA0_B  IN  = M_F_CPU1_SB_CA<0>
  77  VSS33  POWER  = GND
  78  CA2_B  IN  = M_F_CPU1_SB_CA<2>
  79  VSS34  POWER  = GND
  80  CA4_B  IN  = M_F_CPU1_SB_CA<4>
  81  VSS35  POWER  = GND
  82  CA6_B  IN  = M_F_CPU1_SB_CA<6>
  83  VSS36  POWER  = GND
  84  CS0_B_N  IN  = M_F_CPU1_SB_CS_N<0>
  85  VSS37  POWER  = GND
  86  \lbd||rsp_a_n\  OUT  = M_F_CPU1_SA_RSP<0>
  87  \lbs||rsp_b_n\  OUT  = M_F_CPU1_SB_RSP<0>
  88  VSS38  POWER  = GND
  89  CB4_B  BI  = M_F_CPU1_SB_CB<4>
  90  VSS39  POWER  = GND
  91  CB5_B  BI  = M_F_CPU1_SB_CB<5>
  92  VSS40  POWER  = GND
  93  \dqs9_b_t||tdqs9_b_t||dbi4_b_n\  BI  = M_F_CPU1_SB_DQS_DP<9>
  94  \dqs9_b_c||tdqs9_b_c\  BI  = M_F_CPU1_SB_DQS_DN<9>
  95  VSS41  POWER  = GND
  96  CB0_B  BI  = M_F_CPU1_SB_CB<0>
  97  VSS42  POWER  = GND
  98  CB1_B  BI  = M_F_CPU1_SB_CB<1>
  99  VSS43  POWER  = GND
  100  DQ0_B  BI  = M_F_CPU1_SB_DQ<0>
  101  VSS44  POWER  = GND
  102  DQ1_B  BI  = M_F_CPU1_SB_DQ<1>
  103  VSS45  POWER  = GND
  104  DQS0_B_T  BI  = M_F_CPU1_SB_DQS_DP<0>
  105  DQS0_B_C  BI  = M_F_CPU1_SB_DQS_DN<0>
  106  VSS46  POWER  = GND
  107  DQ4_B  BI  = M_F_CPU1_SB_DQ<4>
  108  VSS47  POWER  = GND
  109  DQ5_B  BI  = M_F_CPU1_SB_DQ<5>
  110  VSS48  POWER  = GND
  111  DQ8_B  BI  = M_F_CPU1_SB_DQ<8>
  112  VSS49  POWER  = GND
  113  DQ9_B  BI  = M_F_CPU1_SB_DQ<9>
  114  VSS50  POWER  = GND
  115  DQS1_B_T  BI  = M_F_CPU1_SB_DQS_DP<1>
  116  DQS1_B_C  BI  = M_F_CPU1_SB_DQS_DN<1>
  117  VSS51  POWER  = GND
  118  DQ12_B  BI  = M_F_CPU1_SB_DQ<12>
  119  VSS52  POWER  = GND
  120  DQ13_B  BI  = M_F_CPU1_SB_DQ<13>
  121  VSS53  POWER  = GND
  122  DQ16_B  BI  = M_F_CPU1_SB_DQ<16>
  123  VSS54  POWER  = GND
  124  DQ17_B  BI  = M_F_CPU1_SB_DQ<17>
  125  VSS55  POWER  = GND
  126  DQS2_B_T  BI  = M_F_CPU1_SB_DQS_DP<2>
  127  DQS2_B_C  BI  = M_F_CPU1_SB_DQS_DN<2>
  128  VSS56  POWER  = GND
  129  DQ20_B  BI  = M_F_CPU1_SB_DQ<20>
  130  VSS57  POWER  = GND
  131  DQ21_B  BI  = M_F_CPU1_SB_DQ<21>
  132  VSS58  POWER  = GND
  133  DQ24_B  BI  = M_F_CPU1_SB_DQ<24>
  134  VSS59  POWER  = GND
  135  DQ25_B  BI  = M_F_CPU1_SB_DQ<25>
  136  VSS60  POWER  = GND
  137  DQS3_B_T  BI  = M_F_CPU1_SB_DQS_DP<3>
  138  DQS3_B_C  BI  = M_F_CPU1_SB_DQS_DN<3>
  139  VSS61  POWER  = GND
  140  DQ28_B  BI  = M_F_CPU1_SB_DQ<28>
  141  VSS62  POWER  = GND
  142  DQ29_B  BI  = M_F_CPU1_SB_DQ<29>
  143  VSS63  POWER  = GND
  144  RFU1  TRI  = TP_CHF_CPU1_DIMM1_FRU_1
  145  VIN_BULK1  POWER  = P12V_S3_AUX_CPU1_NVDIMM
  146  VIN_BULK2  POWER  = P12V_S3_AUX_CPU1_NVDIMM
  147  \pwr_good||fail_n\  BI  = PWRGD_CHF_CPU1_DIMM1
  148  HSA  IN  = PD_CHF_CPU1_DIMM1_SAA
  149  RFU2  TRI  = TP_CHF_CPU1_DIMM1_FRU_2
  150  RFU3  TRI  = TP_CHF_CPU1_DIMM1_FRU_3
  151  VSS64  POWER  = GND
  152  DQ2_A  BI  = M_F_CPU1_SA_DQ<2>
  153  VSS65  POWER  = GND
  154  DQ3_A  BI  = M_F_CPU1_SA_DQ<3>
  155  VSS66  POWER  = GND
  156  \dqs5_a_c||tdqs5_a_c||dqs5_a_t||tdqs5_a_t\  BI  = M_F_CPU1_SA_DQS_DN<5>
  157  \dqs5_a_t||tdqs5_a_t\  BI  = M_F_CPU1_SA_DQS_DP<5>
  158  VSS67  POWER  = GND
  159  DQ6_A  BI  = M_F_CPU1_SA_DQ<6>
  160  VSS68  POWER  = GND
  161  DQ7_A  BI  = M_F_CPU1_SA_DQ<7>
  162  VSS69  POWER  = GND
  163  DQ10_A  BI  = M_F_CPU1_SA_DQ<10>
  164  VSS70  POWER  = GND
  165  DQ11_A  BI  = M_F_CPU1_SA_DQ<11>
  166  VSS71  POWER  = GND
  167  \dqs6_a_c||tdqs6_a_c||dqs6_a_t||tdqs6_a_t\  BI  = M_F_CPU1_SA_DQS_DN<6>
  168  \dqs6_a_t||tdqs6_a_t\  BI  = M_F_CPU1_SA_DQS_DP<6>
  169  VSS72  POWER  = GND
  170  DQ14_A  BI  = M_F_CPU1_SA_DQ<14>
  171  VSS73  POWER  = GND
  172  DQ15_A  BI  = M_F_CPU1_SA_DQ<15>
  173  VSS74  POWER  = GND
  174  DQ18_A  BI  = M_F_CPU1_SA_DQ<18>
  175  VSS75  POWER  = GND
  176  DQ19_A  BI  = M_F_CPU1_SA_DQ<19>
  177  VSS76  POWER  = GND
  178  \dqs7_a_c||tdqs7_a_c\  BI  = M_F_CPU1_SA_DQS_DN<7>
  179  \dqs7_a_t||tdqs7_a_t\  BI  = M_F_CPU1_SA_DQS_DP<7>
  180  VSS77  POWER  = GND
  181  DQ22_A  BI  = M_F_CPU1_SA_DQ<22>
  182  VSS78  POWER  = GND
  183  DQ23_A  BI  = M_F_CPU1_SA_DQ<23>
  184  VSS79  POWER  = GND
  185  DQ26_A  BI  = M_F_CPU1_SA_DQ<26>
  186  VSS80  POWER  = GND
  187  DQ27_A  BI  = M_F_CPU1_SA_DQ<27>
  188  VSS81  POWER  = GND
  189  \dqs8_a_c||tdqs8_a_c\  BI  = M_F_CPU1_SA_DQS_DN<8>
  190  \dqs8_a_t||tdqs8_a_t\  BI  = M_F_CPU1_SA_DQS_DP<8>
  191  VSS82  POWER  = GND
  192  DQ30_A  BI  = M_F_CPU1_SA_DQ<30>
  193  VSS83  POWER  = GND
  194  DQ31_A  BI  = M_F_CPU1_SA_DQ<31>
  195  VSS84  POWER  = GND
  196  CB2_A  BI  = M_F_CPU1_SA_CB<2>
  197  VSS85  POWER  = GND
  198  CB3_A  BI  = M_F_CPU1_SA_CB<3>
  199  VSS86  POWER  = GND
  200  \dqs9_a_c||tdqs9_a_c\  BI  = M_F_CPU1_SA_DQS_DN<9>
  201  \dqs9_a_t||tdqs9_a_t\  BI  = M_F_CPU1_SA_DQS_DP<9>
  202  VSS87  POWER  = GND
  203  CB6_A  BI  = M_F_CPU1_SA_CB<6>
  204  VSS88  POWER  = GND
  205  CB7_A  BI  = M_F_CPU1_SA_CB<7>
  206  VSS89  POWER  = GND
  207  RESET_N  IN  = RST_M_EF_CPU1_FPGA_N
  208  VSS90  POWER  = GND
  209  CS1_A_N  IN  = M_F_CPU1_SA_CS_N<1>
  210  VSS91  POWER  = GND
  211  CA1_A  IN  = M_F_CPU1_SA_CA<1>
  212  VSS92  POWER  = GND
  213  CA3_A  IN  = M_F_CPU1_SA_CA<3>
  214  VSS93  POWER  = GND
  215  CA5_A  IN  = M_F_CPU1_SA_CA<5>
  216  VSS94  POWER  = GND
  217  CK_T  IN  = M_F_CPU1_CLK_DP<0>
  218  CK_C  IN  = M_F_CPU1_CLK_DN<0>
  219  VSS95  POWER  = GND
  220  RFU4  TRI  = TP_CHF_CPU1_DIMM1_FRU_4
  221  CA1_B  IN  = M_F_CPU1_SB_CA<1>
  222  VSS96  POWER  = GND
  223  CA3_B  IN  = M_F_CPU1_SB_CA<3>
  224  VSS97  POWER  = GND
  225  CA5_B  IN  = M_F_CPU1_SB_CA<5>
  226  VSS98  POWER  = GND
  227  PAR_B  IN  = M_F_CPU1_SB_PAR
  228  VSS99  POWER  = GND
  229  CS1_B_N  IN  = M_F_CPU1_SB_CS_N<1>
  230  VSS100  POWER  = GND
  231  RFU5  TRI  = TP_CHF_CPU1_DIMM1_FRU_5
  232  RFU6  TRI  = TP_CHF_CPU1_DIMM1_FRU_6
  233  VSS101  POWER  = GND
  234  CB6_B  BI  = M_F_CPU1_SB_CB<6>
  235  VSS102  POWER  = GND
  236  CB7_B  BI  = M_F_CPU1_SB_CB<7>
  237  VSS103  POWER  = GND
  238  DQS4_B_C  BI  = M_F_CPU1_SB_DQS_DN<4>
  239  DQS4_B_T  BI  = M_F_CPU1_SB_DQS_DP<4>
  240  VSS104  POWER  = GND
  241  CB2_B  BI  = M_F_CPU1_SB_CB<2>
  242  VSS105  POWER  = GND
  243  CB3_B  BI  = M_F_CPU1_SB_CB<3>
  244  VSS106  POWER  = GND
  245  DQ2_B  BI  = M_F_CPU1_SB_DQ<2>
  246  VSS107  POWER  = GND
  247  DQ3_B  BI  = M_F_CPU1_SB_DQ<3>
  248  VSS108  POWER  = GND
  249  \dqs5_b_c||tdqs5_b_c\  BI  = M_F_CPU1_SB_DQS_DN<5>
  250  \dqs5_b_t||tdqs5_b_t\  BI  = M_F_CPU1_SB_DQS_DP<5>
  251  VSS109  POWER  = GND
  252  DQ6_B  BI  = M_F_CPU1_SB_DQ<6>
  253  VSS110  POWER  = GND
  254  DQ7_B  BI  = M_F_CPU1_SB_DQ<7>
  255  VSS111  POWER  = GND
  256  DQ10_B  BI  = M_F_CPU1_SB_DQ<10>
  257  VSS112  POWER  = GND
  258  DQ11_B  BI  = M_F_CPU1_SB_DQ<11>
  259  VSS113  POWER  = GND
  260  \dqs6_b_c||tdqs6_b_c\  BI  = M_F_CPU1_SB_DQS_DN<6>
  261  \dqs6_b_t||tdqs6_b_t\  BI  = M_F_CPU1_SB_DQS_DP<6>
  262  VSS114  POWER  = GND
  263  DQ14_B  BI  = M_F_CPU1_SB_DQ<14>
  264  VSS115  POWER  = GND
  265  DQ15_B  BI  = M_F_CPU1_SB_DQ<15>
  266  VSS116  POWER  = GND
  267  DQ18_B  BI  = M_F_CPU1_SB_DQ<18>
  268  VSS117  POWER  = GND
  269  DQ19_B  BI  = M_F_CPU1_SB_DQ<19>
  270  VSS118  POWER  = GND
  271  \dqs7_b_c||tdqs7_b_c\  BI  = M_F_CPU1_SB_DQS_DN<7>
  272  \dqs7_b_t||tdqs7_b_t\  BI  = M_F_CPU1_SB_DQS_DP<7>
  273  VSS119  POWER  = GND
  274  DQ22_B  BI  = M_F_CPU1_SB_DQ<22>
  275  VSS120  POWER  = GND
  276  DQ23_B  BI  = M_F_CPU1_SB_DQ<23>
  277  VSS121  POWER  = GND
  278  DQ26_B  BI  = M_F_CPU1_SB_DQ<26>
  279  VSS122  POWER  = GND
  280  DQ27_B  BI  = M_F_CPU1_SB_DQ<27>
  281  VSS123  POWER  = GND
  282  \dqs8_b_c||tdqs8_b_c\  BI  = M_F_CPU1_SB_DQS_DN<8>
  283  \dqs8_b_t||tdqs8_b_t\  BI  = M_F_CPU1_SB_DQS_DP<8>
  284  VSS124  POWER  = GND
  285  DQ30_B  BI  = M_F_CPU1_SB_DQ<30>
  286  VSS125  POWER  = GND
  287  DQ31_B  BI  = M_F_CPU1_SB_DQ<31>
  288  VSS126  POWER  = GND
  G1  G1  POWER  = GND
  G2  G2  POWER  = GND
  G3  G3  POWER  = GND
